# T6G (Grand Teton) — schematic netlist excerpt (pin names and nets, part order shuffled) for the footprints in the layout excerpt that follows; sources: Cadence DE-HDL packaged netlist, KiCad conversion of 04192023_DAF0TMB3IC0_F0TG_MB_C_brd_V02_OCP.brd

L15  Q_INDUCTOR  BLM18PG300SN1D IND  pkg SMLF  page 257 : \1\ = P3V3_MAX11617_VDD ; \2\ = P3V3_AUX
PC6903  Q_CAP  22UF 16V 20% X6S  pkg C0805  page 361 : A = SW_P12V_AUX_P1V8_RETIMER_CPU1_FLT ; B = GND
C6508  Q_CAP_DIFFBUS  DIFF BUS_0.22UF 6.3V 20% X6S  pkg C0201  page 275 : \1\ = P5E_CPU0_P0_TX_BUF_C_DN<3> ; \2\ = P5E_CPU0_P0_TX_BUF_DN<3>

(kicad_pcb
	(version 20260206)
	(generator "pcbnew")
	(generator_version "10.0")
	(general
		(thickness 1.6)
		(legacy_teardrops no)
	)
	(paper "A4")
	(title_block
		(title "04192023_DAF0TMB3IC0_F0TG_MB_C_brd_V02_OCP.brd")
		(comment 1 "Grand Teton / footprints 3509-3511 of 8354")
	)
	(layers
		(0 "F.Cu" signal "TOP")
		(4 "In1.Cu" signal "GND")
		(6 "In2.Cu" signal "IN1")
		(8 "In3.Cu" signal "GND1")
		(10 "In4.Cu" signal "IN2")
		(12 "In5.Cu" signal "GND2")
		(14 "In6.Cu" signal "IN3")
		(16 "In7.Cu" signal "GND3")
		(18 "In8.Cu" signal "VCC")
		(20 "In9.Cu" signal "VCC1")
		(22 "In10.Cu" signal "GND4")
		(24 "In11.Cu" signal "IN4")
		(26 "In12.Cu" signal "GND5")
		(28 "In13.Cu" signal "IN5")
		(30 "In14.Cu" signal "GND6")
		(32 "In15.Cu" signal "IN6")
		(34 "In16.Cu" signal "GND7")
		(2 "B.Cu" signal "BOTTOM")
		(9 "F.Adhes" user "F.Adhesive")
		(11 "B.Adhes" user "B.Adhesive")
		(13 "F.Paste" user "Package Geometry/Pastemask Top")
		(15 "B.Paste" user "Package Geometry/Pastemask Bottom")
		(5 "F.SilkS" user "Ref Des/Silkscreen Top")
		(7 "B.SilkS" user "Ref Des/Silkscreen Bottom")
		(1 "F.Mask" user "Board Geometry/Soldermask Top")
		(3 "B.Mask" user "Board Geometry/Soldermask Bottom")
		(17 "Dwgs.User" user "User.Drawings")
		(19 "Cmts.User" user "User.Comments")
		(21 "Eco1.User" user "User.Eco1")
		(23 "Eco2.User" user "User.Eco2")
		(25 "Edge.Cuts" user "Board Geometry/Outline")
		(27 "Margin" user)
		(31 "F.CrtYd" user "Package Geometry/Place Bound Top")
		(29 "B.CrtYd" user "Package Geometry/Place Bound Bottom")
		(35 "F.Fab" user "Ref Des/Assembly Top")
		(33 "B.Fab" user "Ref Des/Assembly Bottom")
	)
	(footprint ""
		(layer "F.Cu")
		(at 229.87 -285.64713 180)
		(property "Reference" "PC6903"
			(at 0 0 180)
			(layer "F.SilkS")
			(hide yes)
			(effects
				(font
					(size 1.27 1.27)
				)
			)
		)
		(property "Value" ""
			(at 0 0 180)
			(layer "F.Fab")
			(effects
				(font
					(size 1.27 1.27)
				)
			)
		)
		(duplicate_pad_numbers_are_jumpers no)
		(fp_line
			(start 1.524 0.762)
			(end -1.524 0.762)
			(stroke
				(width 0.1524)
				(type default)
			)
			(layer "F.SilkS")
		)
		(fp_line
			(start 1.524 -0.762)
			(end 1.524 0.762)
			(stroke
				(width 0.1524)
				(type default)
			)
			(layer "F.SilkS")
		)
		(fp_line
			(start -1.524 0.762)
			(end -1.524 -0.762)
			(stroke
				(width 0.1524)
				(type default)
			)
			(layer "F.SilkS")
		)
		(fp_line
			(start -1.524 -0.762)
			(end 1.524 -0.762)
			(stroke
				(width 0.1524)
				(type default)
			)
			(layer "F.SilkS")
		)
		(fp_line
			(start 1.1049 0.724916)
			(end 1.1049 -0.724916)
			(stroke
				(width 0.1)
				(type default)
			)
			(layer "F.Fab")
		)
		(fp_line
			(start 1.1049 -0.724916)
			(end -1.1049 -0.724916)
			(stroke
				(width 0.1)
				(type default)
			)
			(layer "F.Fab")
		)
		(fp_line
			(start -1.1049 0.724916)
			(end 1.1049 0.724916)
			(stroke
				(width 0.1)
				(type default)
			)
			(layer "F.Fab")
		)
		(fp_line
			(start -1.1049 -0.724916)
			(end -1.1049 0.724916)
			(stroke
				(width 0.1)
				(type default)
			)
			(layer "F.Fab")
		)
		(pad "1" smd rect
			(at -0.889 0)
			(size 1.016 1.27)
			(layers "F.Cu" "F.Mask" "F.Paste")
			(net "SW_P12V_AUX_P1V8_RETIMER_CPU1_FLT")
		)
		(pad "2" smd rect
			(at 0.889 0)
			(size 1.016 1.27)
			(layers "F.Cu" "F.Mask" "F.Paste")
			(net "GND")
		)
	)
	(footprint ""
		(layer "F.Cu")
		(at 312.958226 -416.899344 -90)
		(property "Reference" "C6508"
			(at 0 0 270)
			(layer "F.SilkS")
			(hide yes)
			(effects
				(font
					(size 1.27 1.27)
				)
			)
		)
		(property "Value" ""
			(at 0 0 270)
			(layer "F.Fab")
			(effects
				(font
					(size 1.27 1.27)
				)
			)
		)
		(duplicate_pad_numbers_are_jumpers no)
		(fp_line
			(start -0.299974 0.150114)
			(end -0.299974 -0.150114)
			(stroke
				(width 0.1)
				(type default)
			)
			(layer "F.Fab")
		)
		(fp_line
			(start 0.299974 0.150114)
			(end -0.299974 0.150114)
			(stroke
				(width 0.1)
				(type default)
			)
			(layer "F.Fab")
		)
		(fp_line
			(start -0.299974 -0.150114)
			(end 0.299974 -0.150114)
			(stroke
				(width 0.1)
				(type default)
			)
			(layer "F.Fab")
		)
		(fp_line
			(start 0.299974 -0.150114)
			(end 0.299974 0.150114)
			(stroke
				(width 0.1)
				(type default)
			)
			(layer "F.Fab")
		)
		(pad "1" smd rect
			(at -0.2667 0 270)
			(size 0.3048 0.381)
			(layers "F.Cu" "F.Mask" "F.Paste")
			(net "P5E_CPU0_P0_TX_BUF_C_DN<3>")
		)
		(pad "2" smd rect
			(at 0.2667 0 270)
			(size 0.3048 0.381)
			(layers "F.Cu" "F.Mask" "F.Paste")
			(net "P5E_CPU0_P0_TX_BUF_DN<3>")
		)
	)
	(footprint ""
		(layer "F.Cu")
		(at 329.686412 -40.00373)
		(property "Reference" "L15"
			(at 0 0 0)
			(layer "F.SilkS")
			(hide yes)
			(effects
				(font
					(size 1.27 1.27)
				)
			)
		)
		(property "Value" ""
			(at 0 0 0)
			(layer "F.Fab")
			(effects
				(font
					(size 1.27 1.27)
				)
			)
		)
		(duplicate_pad_numbers_are_jumpers no)
		(fp_line
			(start -1.27 -0.5842)
			(end 1.27 -0.5842)
			(stroke
				(width 0.1524)
				(type default)
			)
			(layer "F.SilkS")
		)
		(fp_line
			(start -1.27 -0.5588)
			(end -1.27 -0.5842)
			(stroke
				(width 0.1524)
				(type default)
			)
			(layer "F.SilkS")
		)
		(fp_line
			(start -1.27 0.5842)
			(end -1.27 -0.5842)
			(stroke
				(width 0.1524)
				(type default)
			)
			(layer "F.SilkS")
		)
		(fp_line
			(start 1.27 0.5842)
			(end -1.27 0.5842)
			(stroke
				(width 0.1524)
				(type default)
			)
			(layer "F.SilkS")
		)
		(fp_line
			(start 1.27 0.5842)
			(end 1.27 -0.5842)
			(stroke
				(width 0.1524)
				(type default)
			)
			(layer "F.SilkS")
		)
		(fp_line
			(start -1.194308 -0.406654)
			(end -0.9144 -0.406654)
			(stroke
				(width 0.1)
				(type default)
			)
			(layer "F.Fab")
		)
		(fp_line
			(start -1.194308 0.406654)
			(end -1.194308 -0.406654)
			(stroke
				(width 0.1)
				(type default)
			)
			(layer "F.Fab")
		)
		(fp_line
			(start -0.9144 -0.508)
			(end 0.9144 -0.508)
			(stroke
				(width 0.1)
				(type default)
			)
			(layer "F.Fab")
		)
		(fp_line
			(start -0.9144 -0.406654)
			(end -0.9144 -0.508)
			(stroke
				(width 0.1)
				(type default)
			)
			(layer "F.Fab")
		)
		(fp_line
			(start -0.9144 0.406654)
			(end -1.194308 0.406654)
			(stroke
				(width 0.1)
				(type default)
			)
			(layer "F.Fab")
		)
		(fp_line
			(start -0.9144 0.508)
			(end -0.9144 0.406654)
			(stroke
				(width 0.1)
				(type default)
			)
			(layer "F.Fab")
		)
		(fp_line
			(start 0.9144 -0.508)
			(end 0.9144 -0.406654)
			(stroke
				(width 0.1)
				(type default)
			)
			(layer "F.Fab")
		)
		(fp_line
			(start 0.9144 -0.406654)
			(end 1.1938 -0.406654)
			(stroke
				(width 0.1)
				(type default)
			)
			(layer "F.Fab")
		)
		(fp_line
			(start 0.9144 0.4064)
			(end 0.9144 0.508)
			(stroke
				(width 0.1)
				(type default)
			)
			(layer "F.Fab")
		)
		(fp_line
			(start 0.9144 0.508)
			(end -0.9144 0.508)
			(stroke
				(width 0.1)
				(type default)
			)
			(layer "F.Fab")
		)
		(fp_line
			(start 1.1938 -0.406654)
			(end 1.1938 0.4064)
			(stroke
				(width 0.1)
				(type default)
			)
			(layer "F.Fab")
		)
		(fp_line
			(start 1.1938 0.4064)
			(end 0.9144 0.4064)
			(stroke
				(width 0.1)
				(type default)
			)
			(layer "F.Fab")
		)
		(pad "1" smd rect
			(at -0.7366 0 270)
			(size 0.7112 0.8128)
			(layers "F.Cu" "F.Mask" "F.Paste")
			(net "P3V3_MAX11617_VDD")
		)
		(pad "2" smd rect
			(at 0.7366 0 270)
			(size 0.7112 0.8128)
			(layers "F.Cu" "F.Mask" "F.Paste")
			(net "P3V3_AUX")
		)
	)
)
